(kicad_pcb
	(version 20260206)
	(generator "pcbnew")
	(generator_version "10.0")
	(general
		(thickness 1.6)
		(legacy_teardrops no)
	)
	(paper "A4")
	(title_block
		(title "v2-pdb — ms_pdb_v2.brd")
		(comment 1 "Open CloudServer (Microsoft) / footprints 303-311 of 348")
	)
	(layers
		(0 "F.Cu" signal "TOP")
		(4 "In1.Cu" signal "GND")
		(6 "In2.Cu" signal "IN1")
		(8 "In3.Cu" signal "VCC")
		(10 "In4.Cu" signal "VCC1")
		(12 "In5.Cu" signal "IN2")
		(14 "In6.Cu" signal "GND1")
		(2 "B.Cu" signal "BOTTOM")
		(9 "F.Adhes" user "F.Adhesive")
		(11 "B.Adhes" user "B.Adhesive")
		(13 "F.Paste" user "Package Geometry/Pastemask Top")
		(15 "B.Paste" user "Package Geometry/Pastemask Bottom")
		(5 "F.SilkS" user "Ref Des/Silkscreen Top")
		(7 "B.SilkS" user "Ref Des/Silkscreen Bottom")
		(1 "F.Mask" user "Board Geometry/Soldermask Top")
		(3 "B.Mask" user "Board Geometry/Soldermask Bottom")
		(17 "Dwgs.User" user "User.Drawings")
		(19 "Cmts.User" user "User.Comments")
		(21 "Eco1.User" user "User.Eco1")
		(23 "Eco2.User" user "User.Eco2")
		(25 "Edge.Cuts" user "Board Geometry/Outline")
		(27 "Margin" user)
		(31 "F.CrtYd" user "Package Geometry/Place Bound Top")
		(29 "B.CrtYd" user "Package Geometry/Place Bound Bottom")
		(35 "F.Fab" user "Ref Des/Assembly Top")
		(33 "B.Fab" user "Ref Des/Assembly Bottom")
	)
	(footprint ""
		(layer "F.Cu")
		(at 72.087232 -330.840588 -90)
		(property "Reference" "C50"
			(at 2.751836 -0.146304 90)
			(unlocked yes)
			(layer "F.SilkS")
			(effects
				(font
					(size 0.7874 0.5842)
					(thickness 0.1524)
				)
			)
		)
		(property "Value" ""
			(at 0 0 270)
			(layer "F.Fab")
			(effects
				(font
					(size 1.27 1.27)
				)
			)
		)
		(duplicate_pad_numbers_are_jumpers no)
		(fp_line
			(start -1.2954 0.5842)
			(end -1.2954 -0.5842)
			(stroke
				(width 0.1524)
				(type default)
			)
			(layer "F.SilkS")
		)
		(fp_line
			(start 1.2954 0.5842)
			(end -1.2954 0.5842)
			(stroke
				(width 0.1524)
				(type default)
			)
			(layer "F.SilkS")
		)
		(fp_line
			(start -1.2954 -0.5842)
			(end 1.2954 -0.5842)
			(stroke
				(width 0.1524)
				(type default)
			)
			(layer "F.SilkS")
		)
		(fp_line
			(start 0 -0.5842)
			(end 0 0.5842)
			(stroke
				(width 0.1524)
				(type default)
			)
			(layer "F.SilkS")
		)
		(fp_line
			(start 1.2954 -0.5842)
			(end 1.2954 0.5842)
			(stroke
				(width 0.1524)
				(type default)
			)
			(layer "F.SilkS")
		)
		(fp_poly
			(pts
				(xy 0.8636 -0.4572) (xy 0.8636 -0.3556) (xy 1.143 -0.3556) (xy 1.143 0.3556) (xy 0.8636 0.3556)
				(xy 0.8636 0.4572) (xy -0.8636 0.4572) (xy -0.8636 0.3556) (xy -1.143 0.3556) (xy -1.143 -0.3556)
				(xy -0.8636 -0.3556) (xy -0.8636 -0.4572)
			)
			(stroke
				(width 0)
				(type default)
			)
			(fill no)
			(layer "F.CrtYd")
		)
		(fp_line
			(start -0.884936 0.504952)
			(end -0.884936 -0.504952)
			(stroke
				(width 0.1)
				(type default)
			)
			(layer "F.Fab")
		)
		(fp_line
			(start 0.884936 0.504952)
			(end -0.884936 0.504952)
			(stroke
				(width 0.1)
				(type default)
			)
			(layer "F.Fab")
		)
		(fp_line
			(start -0.884936 -0.504952)
			(end 0.884936 -0.504952)
			(stroke
				(width 0.1)
				(type default)
			)
			(layer "F.Fab")
		)
		(fp_line
			(start 0.884936 -0.504952)
			(end 0.884936 0.504952)
			(stroke
				(width 0.1)
				(type default)
			)
			(layer "F.Fab")
		)
		(pad "1" smd rect
			(at 0.7366 0)
			(size 0.7112 0.8128)
			(layers "F.Cu" "F.Mask" "F.Paste")
			(net "P12V")
		)
		(pad "2" smd rect
			(at -0.7366 0)
			(size 0.7112 0.8128)
			(layers "F.Cu" "F.Mask" "F.Paste")
			(net "GND")
		)
	)
	(footprint ""
		(layer "F.Cu")
		(at 68.697602 -120.313958 180)
		(property "Reference" "R115"
			(at 2.566162 1.311148 0)
			(unlocked yes)
			(layer "F.SilkS")
			(effects
				(font
					(size 0.7874 0.5842)
					(thickness 0.1524)
				)
				(justify left)
			)
		)
		(property "Value" ""
			(at 0 0 180)
			(layer "F.Fab")
			(effects
				(font
					(size 1.27 1.27)
				)
			)
		)
		(duplicate_pad_numbers_are_jumpers no)
		(fp_line
			(start 0.7874 0.4064)
			(end -0.7874 0.4064)
			(stroke
				(width 0.1524)
				(type default)
			)
			(layer "F.SilkS")
		)
		(fp_line
			(start 0.7874 -0.4064)
			(end 0.7874 0.4064)
			(stroke
				(width 0.1524)
				(type default)
			)
			(layer "F.SilkS")
		)
		(fp_line
			(start -0.7874 0.4064)
			(end -0.7874 -0.4064)
			(stroke
				(width 0.1524)
				(type default)
			)
			(layer "F.SilkS")
		)
		(fp_line
			(start -0.7874 -0.4064)
			(end 0.7874 -0.4064)
			(stroke
				(width 0.1524)
				(type default)
			)
			(layer "F.SilkS")
		)
		(fp_poly
			(pts
				(xy -0.508 0.2794) (xy -0.508 0.2286) (xy -0.635 0.2286) (xy -0.635 -0.254) (xy -0.5334 -0.254)
				(xy -0.5334 -0.2794) (xy 0.5334 -0.2794) (xy 0.5334 -0.254) (xy 0.635 -0.254) (xy 0.635 0.254) (xy 0.5334 0.254)
				(xy 0.5334 0.2794)
			)
			(stroke
				(width 0)
				(type default)
			)
			(fill no)
			(layer "F.CrtYd")
		)
		(pad "1" smd rect
			(at 0.40005 0 180)
			(size 0.4572 0.508)
			(layers "F.Cu" "F.Mask" "F.Paste")
			(net "PSU2_REMOTE_R2_P")
		)
		(pad "2" smd rect
			(at -0.40005 0 180)
			(size 0.4572 0.508)
			(layers "F.Cu" "F.Mask" "F.Paste")
			(net "P12V")
		)
	)
	(footprint ""
		(layer "F.Cu")
		(at 74.345292 -285.966154 -90)
		(property "Reference" "C45"
			(at 0.870204 -4.132834 90)
			(unlocked yes)
			(layer "F.SilkS")
			(effects
				(font
					(size 0.7874 0.5842)
					(thickness 0.1524)
				)
				(justify left)
			)
		)
		(property "Value" ""
			(at 0 0 270)
			(layer "F.Fab")
			(effects
				(font
					(size 1.27 1.27)
				)
			)
		)
		(duplicate_pad_numbers_are_jumpers no)
		(fp_line
			(start -0.7874 0.4064)
			(end -0.7874 -0.4064)
			(stroke
				(width 0.1524)
				(type default)
			)
			(layer "F.SilkS")
		)
		(fp_line
			(start 0.7874 0.4064)
			(end -0.7874 0.4064)
			(stroke
				(width 0.1524)
				(type default)
			)
			(layer "F.SilkS")
		)
		(fp_line
			(start 0 0.381)
			(end 0 -0.381)
			(stroke
				(width 0.1524)
				(type default)
			)
			(layer "F.SilkS")
		)
		(fp_line
			(start -0.7874 -0.4064)
			(end 0.7874 -0.4064)
			(stroke
				(width 0.1524)
				(type default)
			)
			(layer "F.SilkS")
		)
		(fp_line
			(start 0.7874 -0.4064)
			(end 0.7874 0.4064)
			(stroke
				(width 0.1524)
				(type default)
			)
			(layer "F.SilkS")
		)
		(fp_poly
			(pts
				(xy -0.5334 0.254) (xy -0.635 0.254) (xy -0.635 0.2286) (xy -0.635 -0.254) (xy -0.5334 -0.254) (xy -0.5334 -0.2794)
				(xy 0.5334 -0.2794) (xy 0.5334 -0.254) (xy 0.635 -0.254) (xy 0.635 0.254) (xy 0.5334 0.254) (xy 0.5334 0.2794)
				(xy -0.508 0.2794) (xy -0.5334 0.2794)
			)
			(stroke
				(width 0)
				(type default)
			)
			(fill no)
			(layer "F.CrtYd")
		)
		(pad "1" smd rect
			(at 0.40005 0 270)
			(size 0.4572 0.508)
			(layers "F.Cu" "F.Mask" "F.Paste")
			(net "P12V")
		)
		(pad "2" smd rect
			(at -0.40005 0 270)
			(size 0.4572 0.508)
			(layers "F.Cu" "F.Mask" "F.Paste")
			(net "GND")
		)
	)
	(footprint ""
		(layer "F.Cu")
		(at 25.804876 -369.095274)
		(property "Reference" "R138"
			(at -3.886962 -0.631952 0)
			(unlocked yes)
			(layer "F.SilkS")
			(effects
				(font
					(size 0.7874 0.5842)
					(thickness 0.1524)
				)
				(justify left)
			)
		)
		(property "Value" ""
			(at 0 0 0)
			(layer "F.Fab")
			(effects
				(font
					(size 1.27 1.27)
				)
			)
		)
		(duplicate_pad_numbers_are_jumpers no)
		(fp_line
			(start -0.7874 -0.4064)
			(end 0.7874 -0.4064)
			(stroke
				(width 0.1524)
				(type default)
			)
			(layer "F.SilkS")
		)
		(fp_line
			(start -0.7874 0.4064)
			(end -0.7874 -0.4064)
			(stroke
				(width 0.1524)
				(type default)
			)
			(layer "F.SilkS")
		)
		(fp_line
			(start 0.7874 -0.4064)
			(end 0.7874 0.4064)
			(stroke
				(width 0.1524)
				(type default)
			)
			(layer "F.SilkS")
		)
		(fp_line
			(start 0.7874 0.4064)
			(end -0.7874 0.4064)
			(stroke
				(width 0.1524)
				(type default)
			)
			(layer "F.SilkS")
		)
		(fp_poly
			(pts
				(xy -0.508 0.2794) (xy -0.508 0.2286) (xy -0.635 0.2286) (xy -0.635 -0.254) (xy -0.5334 -0.254)
				(xy -0.5334 -0.2794) (xy 0.5334 -0.2794) (xy 0.5334 -0.254) (xy 0.635 -0.254) (xy 0.635 0.254) (xy 0.5334 0.254)
				(xy 0.5334 0.2794)
			)
			(stroke
				(width 0)
				(type default)
			)
			(fill no)
			(layer "F.CrtYd")
		)
		(pad "1" smd rect
			(at 0.40005 0)
			(size 0.4572 0.508)
			(layers "F.Cu" "F.Mask" "F.Paste")
			(net "PSU5_CSAHRE")
		)
		(pad "2" smd rect
			(at -0.40005 0)
			(size 0.4572 0.508)
			(layers "F.Cu" "F.Mask" "F.Paste")
			(net "PSU_CSAHRE")
		)
	)
	(footprint ""
		(layer "F.Cu")
		(at 39.85641 -103.52405 180)
		(property "Reference" "R11"
			(at -1.627124 0.025908 0)
			(unlocked yes)
			(layer "F.SilkS")
			(effects
				(font
					(size 0.7874 0.5842)
					(thickness 0.1524)
				)
				(justify left)
			)
		)
		(property "Value" ""
			(at 0 0 180)
			(layer "F.Fab")
			(effects
				(font
					(size 1.27 1.27)
				)
			)
		)
		(duplicate_pad_numbers_are_jumpers no)
		(fp_line
			(start 0.7874 0.4064)
			(end -0.7874 0.4064)
			(stroke
				(width 0.1524)
				(type default)
			)
			(layer "F.SilkS")
		)
		(fp_line
			(start 0.7874 -0.4064)
			(end 0.7874 0.4064)
			(stroke
				(width 0.1524)
				(type default)
			)
			(layer "F.SilkS")
		)
		(fp_line
			(start -0.7874 0.4064)
			(end -0.7874 -0.4064)
			(stroke
				(width 0.1524)
				(type default)
			)
			(layer "F.SilkS")
		)
		(fp_line
			(start -0.7874 -0.4064)
			(end 0.7874 -0.4064)
			(stroke
				(width 0.1524)
				(type default)
			)
			(layer "F.SilkS")
		)
		(fp_poly
			(pts
				(xy -0.508 0.2794) (xy -0.508 0.2286) (xy -0.635 0.2286) (xy -0.635 -0.254) (xy -0.5334 -0.254)
				(xy -0.5334 -0.2794) (xy 0.5334 -0.2794) (xy 0.5334 -0.254) (xy 0.635 -0.254) (xy 0.635 0.254) (xy 0.5334 0.254)
				(xy 0.5334 0.2794)
			)
			(stroke
				(width 0)
				(type default)
			)
			(fill no)
			(layer "F.CrtYd")
		)
		(pad "1" smd rect
			(at 0.40005 0 180)
			(size 0.4572 0.508)
			(layers "F.Cu" "F.Mask" "F.Paste")
			(net "PSU2_RETURN")
		)
		(pad "2" smd rect
			(at -0.40005 0 180)
			(size 0.4572 0.508)
			(layers "F.Cu" "F.Mask" "F.Paste")
			(net "GND")
		)
	)
	(footprint ""
		(layer "F.Cu")
		(at 23.58644 -177.804572 90)
		(property "Reference" "R161"
			(at -1.085342 -4.405884 90)
			(unlocked yes)
			(layer "F.SilkS")
			(effects
				(font
					(size 0.7874 0.5842)
					(thickness 0.1524)
				)
				(justify left)
			)
		)
		(property "Value" ""
			(at 0 0 90)
			(layer "F.Fab")
			(effects
				(font
					(size 1.27 1.27)
				)
			)
		)
		(duplicate_pad_numbers_are_jumpers no)
		(fp_line
			(start 0.7874 -0.4064)
			(end 0.7874 0.4064)
			(stroke
				(width 0.1524)
				(type default)
			)
			(layer "F.SilkS")
		)
		(fp_line
			(start -0.7874 -0.4064)
			(end 0.7874 -0.4064)
			(stroke
				(width 0.1524)
				(type default)
			)
			(layer "F.SilkS")
		)
		(fp_line
			(start 0.7874 0.4064)
			(end -0.7874 0.4064)
			(stroke
				(width 0.1524)
				(type default)
			)
			(layer "F.SilkS")
		)
		(fp_line
			(start -0.7874 0.4064)
			(end -0.7874 -0.4064)
			(stroke
				(width 0.1524)
				(type default)
			)
			(layer "F.SilkS")
		)
		(fp_poly
			(pts
				(xy -0.508 0.2794) (xy -0.508 0.2286) (xy -0.635 0.2286) (xy -0.635 -0.254) (xy -0.5334 -0.254)
				(xy -0.5334 -0.2794) (xy 0.5334 -0.2794) (xy 0.5334 -0.254) (xy 0.635 -0.254) (xy 0.635 0.254) (xy 0.5334 0.254)
				(xy 0.5334 0.2794)
			)
			(stroke
				(width 0)
				(type default)
			)
			(fill no)
			(layer "F.CrtYd")
		)
		(pad "1" smd rect
			(at 0.40005 0 90)
			(size 0.4572 0.508)
			(layers "F.Cu" "F.Mask" "F.Paste")
			(net "N42263600")
		)
		(pad "2" smd rect
			(at -0.40005 0 90)
			(size 0.4572 0.508)
			(layers "F.Cu" "F.Mask" "F.Paste")
			(net "PHLOSS")
		)
	)
	(footprint ""
		(layer "F.Cu")
		(at 46.430692 -238.246666 180)
		(property "Reference" "R88"
			(at 4.272788 0.078232 0)
			(unlocked yes)
			(layer "F.SilkS")
			(effects
				(font
					(size 0.7874 0.5842)
					(thickness 0.1524)
				)
				(justify left)
			)
		)
		(property "Value" ""
			(at 0 0 180)
			(layer "F.Fab")
			(effects
				(font
					(size 1.27 1.27)
				)
			)
		)
		(duplicate_pad_numbers_are_jumpers no)
		(fp_line
			(start 0.7874 0.4064)
			(end -0.7874 0.4064)
			(stroke
				(width 0.1524)
				(type default)
			)
			(layer "F.SilkS")
		)
		(fp_line
			(start 0.7874 -0.4064)
			(end 0.7874 0.4064)
			(stroke
				(width 0.1524)
				(type default)
			)
			(layer "F.SilkS")
		)
		(fp_line
			(start -0.7874 0.4064)
			(end -0.7874 -0.4064)
			(stroke
				(width 0.1524)
				(type default)
			)
			(layer "F.SilkS")
		)
		(fp_line
			(start -0.7874 -0.4064)
			(end 0.7874 -0.4064)
			(stroke
				(width 0.1524)
				(type default)
			)
			(layer "F.SilkS")
		)
		(fp_poly
			(pts
				(xy -0.508 0.2794) (xy -0.508 0.2286) (xy -0.635 0.2286) (xy -0.635 -0.254) (xy -0.5334 -0.254)
				(xy -0.5334 -0.2794) (xy 0.5334 -0.2794) (xy 0.5334 -0.254) (xy 0.635 -0.254) (xy 0.635 0.254) (xy 0.5334 0.254)
				(xy 0.5334 0.2794)
			)
			(stroke
				(width 0)
				(type default)
			)
			(fill no)
			(layer "F.CrtYd")
		)
		(pad "1" smd rect
			(at 0.40005 0 180)
			(size 0.4572 0.508)
			(layers "F.Cu" "F.Mask" "F.Paste")
			(net "PSU1_REMOTE_R_P")
		)
		(pad "2" smd rect
			(at -0.40005 0 180)
			(size 0.4572 0.508)
			(layers "F.Cu" "F.Mask" "F.Paste")
			(net "P12V")
		)
	)
	(footprint ""
		(layer "F.Cu")
		(at 82.499962 -508.115824 -90)
		(property "Reference" "C80"
			(at 3.578606 0.06604 90)
			(unlocked yes)
			(layer "F.SilkS")
			(effects
				(font
					(size 0.7874 0.5842)
					(thickness 0.1524)
				)
				(justify left)
			)
		)
		(property "Value" ""
			(at 0 0 270)
			(layer "F.Fab")
			(effects
				(font
					(size 1.27 1.27)
				)
			)
		)
		(duplicate_pad_numbers_are_jumpers no)
		(fp_line
			(start -0.7874 0.4064)
			(end -0.7874 -0.4064)
			(stroke
				(width 0.1524)
				(type default)
			)
			(layer "F.SilkS")
		)
		(fp_line
			(start 0.7874 0.4064)
			(end -0.7874 0.4064)
			(stroke
				(width 0.1524)
				(type default)
			)
			(layer "F.SilkS")
		)
		(fp_line
			(start 0 0.381)
			(end 0 -0.381)
			(stroke
				(width 0.1524)
				(type default)
			)
			(layer "F.SilkS")
		)
		(fp_line
			(start -0.7874 -0.4064)
			(end 0.7874 -0.4064)
			(stroke
				(width 0.1524)
				(type default)
			)
			(layer "F.SilkS")
		)
		(fp_line
			(start 0.7874 -0.4064)
			(end 0.7874 0.4064)
			(stroke
				(width 0.1524)
				(type default)
			)
			(layer "F.SilkS")
		)
		(fp_poly
			(pts
				(xy -0.5334 0.254) (xy -0.635 0.254) (xy -0.635 0.2286) (xy -0.635 -0.254) (xy -0.5334 -0.254) (xy -0.5334 -0.2794)
				(xy 0.5334 -0.2794) (xy 0.5334 -0.254) (xy 0.635 -0.254) (xy 0.635 0.254) (xy 0.5334 0.254) (xy 0.5334 0.2794)
				(xy -0.508 0.2794) (xy -0.5334 0.2794)
			)
			(stroke
				(width 0)
				(type default)
			)
			(fill no)
			(layer "F.CrtYd")
		)
		(pad "1" smd rect
			(at 0.40005 0 270)
			(size 0.4572 0.508)
			(layers "F.Cu" "F.Mask" "F.Paste")
			(net "P12V")
		)
		(pad "2" smd rect
			(at -0.40005 0 270)
			(size 0.4572 0.508)
			(layers "F.Cu" "F.Mask" "F.Paste")
			(net "GND")
		)
	)
	(footprint ""
		(layer "F.Cu")
		(at 39.849552 -17.30502 180)
		(property "Reference" "R12"
			(at -1.74498 -0.093472 0)
			(unlocked yes)
			(layer "F.SilkS")
			(effects
				(font
					(size 0.7874 0.5842)
					(thickness 0.1524)
				)
				(justify left)
			)
		)
		(property "Value" ""
			(at 0 0 180)
			(layer "F.Fab")
			(effects
				(font
					(size 1.27 1.27)
				)
			)
		)
		(duplicate_pad_numbers_are_jumpers no)
		(fp_line
			(start 0.7874 0.4064)
			(end -0.7874 0.4064)
			(stroke
				(width 0.1524)
				(type default)
			)
			(layer "F.SilkS")
		)
		(fp_line
			(start 0.7874 -0.4064)
			(end 0.7874 0.4064)
			(stroke
				(width 0.1524)
				(type default)
			)
			(layer "F.SilkS")
		)
		(fp_line
			(start -0.7874 0.4064)
			(end -0.7874 -0.4064)
			(stroke
				(width 0.1524)
				(type default)
			)
			(layer "F.SilkS")
		)
		(fp_line
			(start -0.7874 -0.4064)
			(end 0.7874 -0.4064)
			(stroke
				(width 0.1524)
				(type default)
			)
			(layer "F.SilkS")
		)
		(fp_poly
			(pts
				(xy -0.508 0.2794) (xy -0.508 0.2286) (xy -0.635 0.2286) (xy -0.635 -0.254) (xy -0.5334 -0.254)
				(xy -0.5334 -0.2794) (xy 0.5334 -0.2794) (xy 0.5334 -0.254) (xy 0.635 -0.254) (xy 0.635 0.254) (xy 0.5334 0.254)
				(xy 0.5334 0.2794)
			)
			(stroke
				(width 0)
				(type default)
			)
			(fill no)
			(layer "F.CrtYd")
		)
		(pad "1" smd rect
			(at 0.40005 0 180)
			(size 0.4572 0.508)
			(layers "F.Cu" "F.Mask" "F.Paste")
			(net "PSU1_AD0")
		)
		(pad "2" smd rect
			(at -0.40005 0 180)
			(size 0.4572 0.508)
			(layers "F.Cu" "F.Mask" "F.Paste")
			(net "GND")
		)
	)
)
